# BASEBOARD_FAB2 (Tioga Pass) — schematic netlist excerpt (pin names and nets, part order shuffled) for the footprints in the layout excerpt that follows; sources: Cadence DE-HDL packaged netlist, KiCad conversion of Wiwynn_Tioga_Pass_MB.brd

C4D42  CAP  1000PF 50V 10% X7R  pkg 0402LF  page 201 : A = VR_VRRDY_PVCCIN_CPU0 ; B = GND
RF9  RES  1.0K 0.1% CHIP  pkg 0402  page 206 : A = VR_PVCCIN_CPU1_AIREF3 ; B = ISENSE_PVCCIN_CPU1_PH3_IMON
C1G12  ST270U2D5VBM-GP  pkg SMD-TCG2  page 225 : \1\ = VR_FET_SW_P12V_STBY_PVDDQ_GHJ ; \2\ = GND

(kicad_pcb
	(version 20260206)
	(generator "pcbnew")
	(generator_version "10.0")
	(general
		(thickness 1.6)
		(legacy_teardrops no)
	)
	(paper "A4")
	(title_block
		(title "Wiwynn_Tioga_Pass_MB.brd")
		(comment 1 "Tioga Pass / footprints 834-836 of 4770")
	)
	(layers
		(0 "F.Cu" signal "TOP")
		(4 "In1.Cu" signal "L2GND")
		(6 "In2.Cu" signal "L3")
		(8 "In3.Cu" signal "L4GND")
		(10 "In4.Cu" signal "L5")
		(12 "In5.Cu" signal "L6GND")
		(14 "In6.Cu" signal "L7VCC")
		(16 "In7.Cu" signal "L8VCC")
		(18 "In8.Cu" signal "L9GND")
		(20 "In9.Cu" signal "L10")
		(22 "In10.Cu" signal "L11GND")
		(24 "In11.Cu" signal "L12")
		(26 "In12.Cu" signal "L13GND")
		(2 "B.Cu" signal "BOTTOM")
		(9 "F.Adhes" user "F.Adhesive")
		(11 "B.Adhes" user "B.Adhesive")
		(13 "F.Paste" user "Package Geometry/Pastemask Top")
		(15 "B.Paste" user "Package Geometry/Pastemask Bottom")
		(5 "F.SilkS" user "Ref Des/Silkscreen Top")
		(7 "B.SilkS" user "Ref Des/Silkscreen Bottom")
		(1 "F.Mask" user "Board Geometry/Soldermask Top")
		(3 "B.Mask" user "Board Geometry/Soldermask Bottom")
		(17 "Dwgs.User" user "User.Drawings")
		(19 "Cmts.User" user "User.Comments")
		(21 "Eco1.User" user "User.Eco1")
		(23 "Eco2.User" user "User.Eco2")
		(25 "Edge.Cuts" user "Board Geometry/Outline")
		(27 "Margin" user)
		(31 "F.CrtYd" user "Package Geometry/Place Bound Top")
		(29 "B.CrtYd" user "Package Geometry/Place Bound Bottom")
		(35 "F.Fab" user "Ref Des/Assembly Top")
		(33 "B.Fab" user "Ref Des/Assembly Bottom")
	)
	(footprint ""
		(layer "F.Cu")
		(at 179.578 -67.437 -90)
		(property "Reference" "C4D42"
			(at 0 0 270)
			(layer "F.SilkS")
			(hide yes)
			(effects
				(font
					(size 1.27 1.27)
				)
			)
		)
		(property "Value" ""
			(at 0 0 270)
			(layer "F.Fab")
			(effects
				(font
					(size 1.27 1.27)
				)
			)
		)
		(duplicate_pad_numbers_are_jumpers no)
		(fp_poly
			(pts
				(xy 0.3048 -0.1016) (xy 0.3048 0.9906) (xy -0.3048 0.9906) (xy -0.3048 -0.1016)
			)
			(stroke
				(width 0)
				(type default)
			)
			(fill no)
			(layer "F.CrtYd")
		)
		(fp_line
			(start -0.3048 0.9906)
			(end 0.3048 0.9906)
			(stroke
				(width 0.1)
				(type default)
			)
			(layer "F.Fab")
		)
		(fp_line
			(start 0.3048 0.9906)
			(end 0.3048 -0.1016)
			(stroke
				(width 0.1)
				(type default)
			)
			(layer "F.Fab")
		)
		(fp_line
			(start -0.3048 -0.1016)
			(end -0.3048 0.9906)
			(stroke
				(width 0.1)
				(type default)
			)
			(layer "F.Fab")
		)
		(fp_line
			(start 0.3048 -0.1016)
			(end -0.3048 -0.1016)
			(stroke
				(width 0.1)
				(type default)
			)
			(layer "F.Fab")
		)
		(pad "1" smd rect
			(at 0 0 270)
			(size 0.508 0.508)
			(layers "F.Cu" "F.Mask" "F.Paste")
			(net "VR_VRRDY_PVCCIN_CPU0")
		)
		(pad "2" smd rect
			(at 0 0.889 270)
			(size 0.508 0.508)
			(layers "F.Cu" "F.Mask" "F.Paste")
			(net "GND")
		)
		(zone
			(layer "F.Cu")
			(hatch none 0.5)
			(connect_pads
				(clearance 0)
			)
			(min_thickness 0.25)
			(keepout
				(tracks not_allowed)
				(vias allowed)
				(pads allowed)
				(copperpour not_allowed)
				(footprints allowed)
			)
			(placement
				(enabled no)
				(sheetname "")
			)
			(fill
				(thermal_gap 0.5)
				(thermal_bridge_width 0.5)
				(island_removal_mode 0)
			)
			(polygon
				(pts
					(xy 178.943 -67.691) (xy 178.943 -67.183) (xy 179.324 -67.183) (xy 179.324 -67.691)
				)
			)
		)
		(zone
			(layer "F.Cu")
			(hatch none 0.5)
			(connect_pads
				(clearance 0)
			)
			(min_thickness 0.25)
			(keepout
				(tracks allowed)
				(vias not_allowed)
				(pads allowed)
				(copperpour not_allowed)
				(footprints allowed)
			)
			(placement
				(enabled no)
				(sheetname "")
			)
			(fill
				(thermal_gap 0.5)
				(thermal_bridge_width 0.5)
				(island_removal_mode 0)
			)
			(polygon
				(pts
					(xy 179.324 -67.691) (xy 179.324 -67.183) (xy 178.943 -67.183) (xy 178.943 -67.691)
				)
			)
		)
	)
	(footprint ""
		(layer "F.Cu")
		(at 24.03602 -89.7509 180)
		(property "Reference" "RF9"
			(at -0.8382 -0.67818 180)
			(unlocked yes)
			(layer "F.SilkS")
			(effects
				(font
					(size 0.4064 0.254)
					(thickness 0.1524)
				)
				(justify left)
			)
		)
		(property "Value" ""
			(at 0 0 180)
			(layer "F.Fab")
			(effects
				(font
					(size 1.27 1.27)
				)
			)
		)
		(duplicate_pad_numbers_are_jumpers no)
		(fp_poly
			(pts
				(xy -0.2794 -0.1016) (xy 0.2794 -0.1016) (xy 0.2794 0.9906) (xy -0.2794 0.9906)
			)
			(stroke
				(width 0)
				(type default)
			)
			(fill no)
			(layer "F.CrtYd")
		)
		(fp_line
			(start 0.2794 0.9906)
			(end 0.2794 -0.1016)
			(stroke
				(width 0.1)
				(type default)
			)
			(layer "F.Fab")
		)
		(fp_line
			(start 0.2794 -0.1016)
			(end -0.2794 -0.1016)
			(stroke
				(width 0.1)
				(type default)
			)
			(layer "F.Fab")
		)
		(fp_line
			(start -0.2794 0.9906)
			(end 0.2794 0.9906)
			(stroke
				(width 0.1)
				(type default)
			)
			(layer "F.Fab")
		)
		(fp_line
			(start -0.2794 -0.1016)
			(end -0.2794 0.9906)
			(stroke
				(width 0.1)
				(type default)
			)
			(layer "F.Fab")
		)
		(pad "1" smd rect
			(at 0 0 180)
			(size 0.508 0.508)
			(layers "F.Cu" "F.Mask" "F.Paste")
			(net "VR_PVCCIN_CPU1_AIREF3")
		)
		(pad "2" smd rect
			(at 0 0.889 180)
			(size 0.508 0.508)
			(layers "F.Cu" "F.Mask" "F.Paste")
			(net "ISENSE_PVCCIN_CPU1_PH3_IMON")
		)
		(zone
			(layer "F.Cu")
			(hatch none 0.5)
			(connect_pads
				(clearance 0)
			)
			(min_thickness 0.25)
			(keepout
				(tracks not_allowed)
				(vias allowed)
				(pads allowed)
				(copperpour not_allowed)
				(footprints allowed)
			)
			(placement
				(enabled no)
				(sheetname "")
			)
			(fill
				(thermal_gap 0.5)
				(thermal_bridge_width 0.5)
				(island_removal_mode 0)
			)
			(polygon
				(pts
					(xy 24.29002 -90.3859) (xy 23.78202 -90.3859) (xy 23.78202 -90.0049) (xy 24.29002 -90.0049)
				)
			)
		)
		(zone
			(layer "F.Cu")
			(hatch none 0.5)
			(connect_pads
				(clearance 0)
			)
			(min_thickness 0.25)
			(keepout
				(tracks allowed)
				(vias not_allowed)
				(pads allowed)
				(copperpour not_allowed)
				(footprints allowed)
			)
			(placement
				(enabled no)
				(sheetname "")
			)
			(fill
				(thermal_gap 0.5)
				(thermal_bridge_width 0.5)
				(island_removal_mode 0)
			)
			(polygon
				(pts
					(xy 24.29002 -90.0049) (xy 23.78202 -90.0049) (xy 23.78202 -90.3859) (xy 24.29002 -90.3859)
				)
			)
		)
	)
	(footprint ""
		(layer "F.Cu")
		(at -2.8702 -10.8077 -90)
		(property "Reference" "C1G12"
			(at 0 0 270)
			(layer "F.SilkS")
			(hide yes)
			(effects
				(font
					(size 1.27 1.27)
				)
			)
		)
		(property "Value" "*"
			(at -2.3114 0.10795 270)
			(unlocked yes)
			(layer "F.Fab")
			(hide yes)
			(effects
				(font
					(size 0.889 0.889)
					(thickness 0.1524)
				)
			)
		)
		(property "Device Type" "ST270U2D5VBM-GP_SMD-TCG2-ST270A"
			(at -2.3114 -1.41605 270)
			(unlocked yes)
			(layer "F.Fab")
			(hide yes)
			(effects
				(font
					(size 0.889 0.889)
					(thickness 0.1524)
				)
			)
		)
		(duplicate_pad_numbers_are_jumpers no)
		(fp_line
			(start -1.5494 0.4826)
			(end -1.5494 -0.4826)
			(stroke
				(width 0.1524)
				(type default)
			)
			(layer "F.SilkS")
		)
		(fp_line
			(start 1.5494 -0.4826)
			(end 1.5494 0.4826)
			(stroke
				(width 0.1524)
				(type default)
			)
			(layer "F.SilkS")
		)
		(fp_line
			(start -1.0922 -2.35458)
			(end 1.0922 -2.35458)
			(stroke
				(width 0.508)
				(type default)
			)
			(layer "F.SilkS")
		)
		(fp_poly
			(pts
				(xy -1.3462 1.9558) (xy -1.3462 1.905) (xy -1.5494 1.905) (xy -1.5494 -1.905) (xy -1.3462 -1.905)
				(xy -1.3462 -1.9558) (xy 1.3462 -1.9558) (xy 1.3462 -1.905) (xy 1.5494 -1.905) (xy 1.5494 1.905)
				(xy 1.3462 1.905) (xy 1.3462 1.9558)
			)
			(stroke
				(width 0)
				(type default)
			)
			(fill no)
			(layer "F.CrtYd")
		)
		(fp_poly
			(pts
				(xy -1.3462 1.9558) (xy -1.3462 1.905) (xy -1.5494 1.905) (xy -1.5494 -1.905) (xy -1.3462 -1.905)
				(xy -1.3462 -1.9558) (xy 1.3462 -1.9558) (xy 1.3462 -1.905) (xy 1.5494 -1.905) (xy 1.5494 1.905)
				(xy 1.3462 1.905) (xy 1.3462 1.9558)
			)
			(stroke
				(width 0)
				(type default)
			)
			(fill no)
			(layer "F.Fab")
		)
		(pad "1" smd rect
			(at 0 -1.27508 270)
			(size 2.6924 1.3462)
			(layers "F.Cu" "F.Mask" "F.Paste")
			(net "VR_FET_SW_P12V_STBY_PVDDQ_GHJ")
		)
		(pad "2" smd rect
			(at 0 1.27508 270)
			(size 2.6924 1.3462)
			(layers "F.Cu" "F.Mask" "F.Paste")
			(net "GND")
		)
	)
)
